# SCM (Grand Teton) — schematic netlist excerpt (pin names and nets, part order shuffled) for the footprints in the layout excerpt that follows; sources: Cadence DE-HDL packaged netlist, KiCad conversion of 12092022_DA0F0TMDCD0_F0T_Management_Board_D_brd_V3_OCP.brd

C45  Q_CAP  0.1UF 25V 10% X7R  pkg 0402  page 15 : A = P3V3_BMC_USB2AV33 ; B = GND
R610  Q_RES  2.2K 5% CHIP  pkg 0402LF  page 27 : A = P3V3_AUX ; B = SMB_BMC_MM15_SCL

(kicad_pcb
	(version 20260206)
	(generator "pcbnew")
	(generator_version "10.0")
	(general
		(thickness 1.6)
		(legacy_teardrops no)
	)
	(paper "A4")
	(title_block
		(title "12092022_DA0F0TMDCD0_F0T_Management_Board_D_brd_V3_OCP.brd")
		(comment 1 "Grand Teton / footprints 1029-1030 of 1440")
	)
	(layers
		(0 "F.Cu" signal "TOP")
		(4 "In1.Cu" signal "GND")
		(6 "In2.Cu" signal "IN1")
		(8 "In3.Cu" signal "GND1")
		(10 "In4.Cu" signal "IN2")
		(12 "In5.Cu" signal "VCC")
		(14 "In6.Cu" signal "VCC1")
		(16 "In7.Cu" signal "IN3")
		(18 "In8.Cu" signal "GND2")
		(20 "In9.Cu" signal "IN4")
		(22 "In10.Cu" signal "GND3")
		(2 "B.Cu" signal "BOTTOM")
		(9 "F.Adhes" user "F.Adhesive")
		(11 "B.Adhes" user "B.Adhesive")
		(13 "F.Paste" user "Package Geometry/Pastemask Top")
		(15 "B.Paste" user "Package Geometry/Pastemask Bottom")
		(5 "F.SilkS" user "Ref Des/Silkscreen Top")
		(7 "B.SilkS" user "Ref Des/Silkscreen Bottom")
		(1 "F.Mask" user "Board Geometry/Soldermask Top")
		(3 "B.Mask" user "Board Geometry/Soldermask Bottom")
		(17 "Dwgs.User" user "User.Drawings")
		(19 "Cmts.User" user "User.Comments")
		(21 "Eco1.User" user "User.Eco1")
		(23 "Eco2.User" user "User.Eco2")
		(25 "Edge.Cuts" user "Board Geometry/Outline")
		(27 "Margin" user)
		(31 "F.CrtYd" user "Package Geometry/Place Bound Top")
		(29 "B.CrtYd" user "Package Geometry/Place Bound Bottom")
		(35 "F.Fab" user "Ref Des/Assembly Top")
		(33 "B.Fab" user "Ref Des/Assembly Bottom")
	)
	(footprint ""
		(layer "B.Cu")
		(at 48.624236 -30.857698 -90)
		(property "Reference" "R610"
			(at 0 0 90)
			(layer "B.SilkS")
			(hide yes)
			(effects
				(font
					(size 1.27 1.27)
				)
				(justify mirror)
			)
		)
		(property "Value" ""
			(at 0 0 90)
			(layer "B.Fab")
			(effects
				(font
					(size 1.27 1.27)
				)
				(justify mirror)
			)
		)
		(duplicate_pad_numbers_are_jumpers no)
		(fp_line
			(start -0.7874 0.4064)
			(end 0.7874 0.4064)
			(stroke
				(width 0.1524)
				(type default)
			)
			(layer "B.SilkS")
		)
		(fp_line
			(start 0.7874 0.4064)
			(end 0.7874 -0.4064)
			(stroke
				(width 0.1524)
				(type default)
			)
			(layer "B.SilkS")
		)
		(fp_line
			(start -0.7874 -0.4064)
			(end -0.7874 0.4064)
			(stroke
				(width 0.1524)
				(type default)
			)
			(layer "B.SilkS")
		)
		(fp_line
			(start 0.7874 -0.4064)
			(end -0.7874 -0.4064)
			(stroke
				(width 0.1524)
				(type default)
			)
			(layer "B.SilkS")
		)
		(fp_line
			(start -0.67945 0.3048)
			(end -0.120396 0.3048)
			(stroke
				(width 0.1)
				(type default)
			)
			(layer "B.Fab")
		)
		(fp_line
			(start -0.120396 0.3048)
			(end -0.120396 0.2794)
			(stroke
				(width 0.1)
				(type default)
			)
			(layer "B.Fab")
		)
		(fp_line
			(start 0.12065 0.3048)
			(end 0.67945 0.3048)
			(stroke
				(width 0.1)
				(type default)
			)
			(layer "B.Fab")
		)
		(fp_line
			(start 0.67945 0.3048)
			(end 0.67945 -0.305054)
			(stroke
				(width 0.1)
				(type default)
			)
			(layer "B.Fab")
		)
		(fp_line
			(start -0.120396 0.2794)
			(end 0.12065 0.2794)
			(stroke
				(width 0.1)
				(type default)
			)
			(layer "B.Fab")
		)
		(fp_line
			(start 0.12065 0.2794)
			(end 0.12065 0.3048)
			(stroke
				(width 0.1)
				(type default)
			)
			(layer "B.Fab")
		)
		(fp_line
			(start -0.12065 -0.2794)
			(end -0.12065 -0.3048)
			(stroke
				(width 0.1)
				(type default)
			)
			(layer "B.Fab")
		)
		(fp_line
			(start 0.12065 -0.2794)
			(end -0.12065 -0.2794)
			(stroke
				(width 0.1)
				(type default)
			)
			(layer "B.Fab")
		)
		(fp_line
			(start -0.67945 -0.3048)
			(end -0.67945 0.3048)
			(stroke
				(width 0.1)
				(type default)
			)
			(layer "B.Fab")
		)
		(fp_line
			(start -0.12065 -0.3048)
			(end -0.67945 -0.3048)
			(stroke
				(width 0.1)
				(type default)
			)
			(layer "B.Fab")
		)
		(fp_line
			(start 0.12065 -0.305054)
			(end 0.12065 -0.2794)
			(stroke
				(width 0.1)
				(type default)
			)
			(layer "B.Fab")
		)
		(fp_line
			(start 0.67945 -0.305054)
			(end 0.12065 -0.305054)
			(stroke
				(width 0.1)
				(type default)
			)
			(layer "B.Fab")
		)
		(pad "1" smd circle
			(at 0.40005 0 90)
			(size 0 0)
			(layers "B.Cu" "B.Mask" "B.Paste")
			(net "P3V3_AUX")
		)
		(pad "2" smd circle
			(at -0.40005 0 90)
			(size 0 0)
			(layers "B.Cu" "B.Mask" "B.Paste")
			(net "SMB_BMC_MM15_SCL")
		)
	)
	(footprint ""
		(layer "B.Cu")
		(at 59.042554 -45.939964 180)
		(property "Reference" "C45"
			(at 0 0 0)
			(layer "B.SilkS")
			(hide yes)
			(effects
				(font
					(size 1.27 1.27)
				)
				(justify mirror)
			)
		)
		(property "Value" ""
			(at 0 0 0)
			(layer "B.Fab")
			(effects
				(font
					(size 1.27 1.27)
				)
				(justify mirror)
			)
		)
		(duplicate_pad_numbers_are_jumpers no)
		(fp_line
			(start 0.7874 0.4064)
			(end 0.7874 -0.4064)
			(stroke
				(width 0.1524)
				(type default)
			)
			(layer "B.SilkS")
		)
		(fp_line
			(start 0.7874 -0.4064)
			(end -0.7874 -0.4064)
			(stroke
				(width 0.1524)
				(type default)
			)
			(layer "B.SilkS")
		)
		(fp_line
			(start -0.7874 0.4064)
			(end 0.7874 0.4064)
			(stroke
				(width 0.1524)
				(type default)
			)
			(layer "B.SilkS")
		)
		(fp_line
			(start -0.7874 -0.4064)
			(end -0.7874 0.4064)
			(stroke
				(width 0.1524)
				(type default)
			)
			(layer "B.SilkS")
		)
		(fp_line
			(start 0.67945 0.3048)
			(end 0.67945 -0.305054)
			(stroke
				(width 0.1)
				(type default)
			)
			(layer "B.Fab")
		)
		(fp_line
			(start 0.67945 -0.305054)
			(end 0.12065 -0.305054)
			(stroke
				(width 0.1)
				(type default)
			)
			(layer "B.Fab")
		)
		(fp_line
			(start 0.12065 0.3048)
			(end 0.67945 0.3048)
			(stroke
				(width 0.1)
				(type default)
			)
			(layer "B.Fab")
		)
		(fp_line
			(start 0.12065 0.2794)
			(end 0.12065 0.3048)
			(stroke
				(width 0.1)
				(type default)
			)
			(layer "B.Fab")
		)
		(fp_line
			(start 0.12065 -0.2794)
			(end -0.12065 -0.2794)
			(stroke
				(width 0.1)
				(type default)
			)
			(layer "B.Fab")
		)
		(fp_line
			(start 0.12065 -0.305054)
			(end 0.12065 -0.2794)
			(stroke
				(width 0.1)
				(type default)
			)
			(layer "B.Fab")
		)
		(fp_line
			(start -0.120396 0.3048)
			(end -0.120396 0.2794)
			(stroke
				(width 0.1)
				(type default)
			)
			(layer "B.Fab")
		)
		(fp_line
			(start -0.120396 0.2794)
			(end 0.12065 0.2794)
			(stroke
				(width 0.1)
				(type default)
			)
			(layer "B.Fab")
		)
		(fp_line
			(start -0.12065 -0.2794)
			(end -0.12065 -0.3048)
			(stroke
				(width 0.1)
				(type default)
			)
			(layer "B.Fab")
		)
		(fp_line
			(start -0.12065 -0.3048)
			(end -0.67945 -0.3048)
			(stroke
				(width 0.1)
				(type default)
			)
			(layer "B.Fab")
		)
		(fp_line
			(start -0.67945 0.3048)
			(end -0.120396 0.3048)
			(stroke
				(width 0.1)
				(type default)
			)
			(layer "B.Fab")
		)
		(fp_line
			(start -0.67945 -0.3048)
			(end -0.67945 0.3048)
			(stroke
				(width 0.1)
				(type default)
			)
			(layer "B.Fab")
		)
		(pad "1" smd circle
			(at 0.40005 0)
			(size 0 0)
			(layers "B.Cu" "B.Mask" "B.Paste")
			(net "P3V3_BMC_USB2AV33")
		)
		(pad "2" smd circle
			(at -0.40005 0)
			(size 0 0)
			(layers "B.Cu" "B.Mask" "B.Paste")
			(net "GND")
		)
	)
)
